#ISCELL
  pure_quanta quanta_title_block_c *
  *
#ISCELL
  standard offpage *
  page432_i1
#CELL
  pure_quanta q_res *
  page432_i18
#ISCELL
  pure_quanta_power universal_gnd *
  page432_i19
#ISCELL
  standard offpage *
  page432_i2
#ISCELL
  pure_quanta_power universal_gnd *
  page432_i20
#ISCELL
  pure_quanta_power universal_gnd *
  page432_i21
#ISCELL
  pure_quanta_power p1v0 *
  page432_i22
#CELL
  pure_quanta q_cap *
  page432_i23
#ISCELL
  pure_quanta_power universal_gnd *
  page432_i24
#CELL
  pure_quanta q_res *
  page432_i3
#CELL
  pure_quanta q_res *
  page432_i4
#CELL
  pure_quanta m24m02drmn6tp *
  page432_i5
